(kicad_pcb
	(version 20260206)
	(generator "pcbnew")
	(generator_version "10.0")
	(general
		(thickness 1.6)
		(legacy_teardrops no)
	)
	(paper "A4")
	(title_block
		(title "4HDD Backplane_Layout.brd")
		(comment 1 "Tioga Pass / footprints 65-70 of 97")
	)
	(layers
		(0 "F.Cu" signal "TOP")
		(4 "In1.Cu" signal "L2GND")
		(6 "In2.Cu" signal "L3")
		(8 "In3.Cu" signal "L4")
		(10 "In4.Cu" signal "L5GND")
		(2 "B.Cu" signal "BOTTOM")
		(9 "F.Adhes" user "F.Adhesive")
		(11 "B.Adhes" user "B.Adhesive")
		(13 "F.Paste" user "Package Geometry/Pastemask Top")
		(15 "B.Paste" user "Package Geometry/Pastemask Bottom")
		(5 "F.SilkS" user "Ref Des/Silkscreen Top")
		(7 "B.SilkS" user "Ref Des/Silkscreen Bottom")
		(1 "F.Mask" user "Board Geometry/Soldermask Top")
		(3 "B.Mask" user "Board Geometry/Soldermask Bottom")
		(17 "Dwgs.User" user "User.Drawings")
		(19 "Cmts.User" user "User.Comments")
		(21 "Eco1.User" user "User.Eco1")
		(23 "Eco2.User" user "User.Eco2")
		(25 "Edge.Cuts" user "Board Geometry/Outline")
		(27 "Margin" user)
		(31 "F.CrtYd" user "Package Geometry/Place Bound Top")
		(29 "B.CrtYd" user "Package Geometry/Place Bound Bottom")
		(35 "F.Fab" user "Ref Des/Assembly Top")
		(33 "B.Fab" user "Ref Des/Assembly Bottom")
	)
	(footprint ""
		(layer "F.Cu")
		(at 55.726076 -19.040348 -90)
		(property "Reference" "R12"
			(at 0 0 270)
			(layer "F.SilkS")
			(hide yes)
			(effects
				(font
					(size 1.27 1.27)
				)
			)
		)
		(property "Value" "10R3F-GP"
			(at -0.0254 -2.5146 270)
			(unlocked yes)
			(layer "F.Fab")
			(hide yes)
			(effects
				(font
					(size 1.016 1.016)
					(thickness 0.1524)
				)
			)
		)
		(property "Device Type" "R603H22"
			(at -0.0254 -4.0386 270)
			(unlocked yes)
			(layer "F.Fab")
			(hide yes)
			(effects
				(font
					(size 1.016 1.016)
					(thickness 0.1524)
				)
			)
		)
		(duplicate_pad_numbers_are_jumpers no)
		(fp_line
			(start -0.4826 0)
			(end -0.2032 0)
			(stroke
				(width 0.2032)
				(type default)
			)
			(layer "F.SilkS")
		)
		(fp_line
			(start 0.2032 0)
			(end 0.4826 0)
			(stroke
				(width 0.2032)
				(type default)
			)
			(layer "F.SilkS")
		)
		(fp_rect
			(start -0.5842 1.3335)
			(end 0.5842 -1.3335)
			(stroke
				(width 0)
				(type default)
			)
			(fill no)
			(layer "F.CrtYd")
		)
		(fp_rect
			(start -0.5842 1.3335)
			(end 0.5842 -1.3335)
			(stroke
				(width 0)
				(type default)
			)
			(fill no)
			(layer "F.Fab")
		)
		(pad "1" smd custom
			(at 0 -0.762 270)
			(size 0.2159 0.2159)
			(layers "F.Cu" "F.Mask" "F.Paste")
			(net "P12V_SW_L")
			(options
				(clearance outline)
				(anchor circle)
			)
			(primitives
				(gr_poly
					(pts
						(arc
							(start -0.3302 -0.4318)
							(mid -0.402042 -0.402042)
							(end -0.4318 -0.3302)
						)
						(arc
							(start -0.4318 0.3302)
							(mid -0.402042 0.402042)
							(end -0.3302 0.4318)
						)
						(arc
							(start 0.3302 0.4318)
							(mid 0.402042 0.402042)
							(end 0.4318 0.3302)
						)
						(arc
							(start 0.4318 -0.3302)
							(mid 0.402042 -0.402042)
							(end 0.3302 -0.4318)
						)
					)
					(width 0)
					(fill yes)
				)
			)
		)
		(pad "2" smd custom
			(at 0 0.762 270)
			(size 0.2159 0.2159)
			(layers "F.Cu" "F.Mask" "F.Paste")
			(net "12V_PRE_2")
			(options
				(clearance outline)
				(anchor circle)
			)
			(primitives
				(gr_poly
					(pts
						(arc
							(start -0.3302 -0.4318)
							(mid -0.402042 -0.402042)
							(end -0.4318 -0.3302)
						)
						(arc
							(start -0.4318 0.3302)
							(mid -0.402042 0.402042)
							(end -0.3302 0.4318)
						)
						(arc
							(start 0.3302 0.4318)
							(mid 0.402042 0.402042)
							(end 0.4318 0.3302)
						)
						(arc
							(start 0.4318 -0.3302)
							(mid 0.402042 -0.402042)
							(end 0.3302 -0.4318)
						)
					)
					(width 0)
					(fill yes)
				)
			)
		)
	)
	(footprint ""
		(layer "B.Cu")
		(at 69.144134 -6.621526 180)
		(property "Reference" "Q9"
			(at 0 0 0)
			(layer "B.SilkS")
			(hide yes)
			(effects
				(font
					(size 1.27 1.27)
				)
				(justify mirror)
			)
		)
		(property "Value" "2N7002K-1-GP"
			(at -0.127 -8.9662 180)
			(unlocked yes)
			(layer "B.Fab")
			(hide yes)
			(effects
				(font
					(size 1.016 1.016)
					(thickness 0.1524)
				)
				(justify mirror)
			)
		)
		(property "Device Type" "SOT23DGS2D4H44"
			(at -0.127 -10.4902 180)
			(unlocked yes)
			(layer "B.Fab")
			(hide yes)
			(effects
				(font
					(size 1.016 1.016)
					(thickness 0.1524)
				)
				(justify mirror)
			)
		)
		(duplicate_pad_numbers_are_jumpers no)
		(fp_line
			(start 1.651 1.778)
			(end -1.651 1.778)
			(stroke
				(width 0.1524)
				(type default)
			)
			(layer "B.SilkS")
		)
		(fp_line
			(start 1.651 -1.778)
			(end 1.651 1.778)
			(stroke
				(width 0.1524)
				(type default)
			)
			(layer "B.SilkS")
		)
		(fp_line
			(start -1.651 1.778)
			(end -1.651 -1.778)
			(stroke
				(width 0.1524)
				(type default)
			)
			(layer "B.SilkS")
		)
		(fp_line
			(start -1.651 -1.778)
			(end 1.651 -1.778)
			(stroke
				(width 0.1524)
				(type default)
			)
			(layer "B.SilkS")
		)
		(fp_poly
			(pts
				(xy 1.778 1.8796) (xy 1.778 -1.8796) (xy -1.778 -1.8796) (xy -1.778 1.8796)
			)
			(stroke
				(width 0)
				(type default)
			)
			(fill no)
			(layer "B.CrtYd")
		)
		(fp_poly
			(pts
				(xy 1.778 1.8796) (xy 1.778 -1.8796) (xy -1.778 -1.8796) (xy -1.778 1.8796)
			)
			(stroke
				(width 0)
				(type default)
			)
			(fill no)
			(layer "B.Fab")
		)
		(pad "D" smd custom
			(at 0 -0.9525)
			(size 0.1905 0.1905)
			(layers "B.Cu" "B.Mask" "B.Paste")
			(net "PWR_EN_L_P5V")
			(options
				(clearance outline)
				(anchor circle)
			)
			(primitives
				(gr_poly
					(pts
						(arc
							(start -0.1778 -0.5715)
							(mid -0.321484 -0.511984)
							(end -0.381 -0.3683)
						)
						(arc
							(start -0.381 0.3683)
							(mid -0.321484 0.511984)
							(end -0.1778 0.5715)
						)
						(arc
							(start 0.1778 0.5715)
							(mid 0.321484 0.511984)
							(end 0.381 0.3683)
						)
						(arc
							(start 0.381 -0.3683)
							(mid 0.321484 -0.511984)
							(end 0.1778 -0.5715)
						)
					)
					(width 0)
					(fill yes)
				)
			)
		)
		(pad "G" smd custom
			(at 0.98425 0.9525)
			(size 0.1905 0.1905)
			(layers "B.Cu" "B.Mask" "B.Paste")
			(net "PWR_EN_L_DELAY")
			(options
				(clearance outline)
				(anchor circle)
			)
			(primitives
				(gr_poly
					(pts
						(arc
							(start -0.1778 -0.5715)
							(mid -0.321484 -0.511984)
							(end -0.381 -0.3683)
						)
						(arc
							(start -0.381 0.3683)
							(mid -0.321484 0.511984)
							(end -0.1778 0.5715)
						)
						(arc
							(start 0.1778 0.5715)
							(mid 0.321484 0.511984)
							(end 0.381 0.3683)
						)
						(arc
							(start 0.381 -0.3683)
							(mid 0.321484 -0.511984)
							(end 0.1778 -0.5715)
						)
					)
					(width 0)
					(fill yes)
				)
			)
		)
		(pad "S" smd custom
			(at -0.98425 0.9525)
			(size 0.1905 0.1905)
			(layers "B.Cu" "B.Mask" "B.Paste")
			(net "GND")
			(options
				(clearance outline)
				(anchor circle)
			)
			(primitives
				(gr_poly
					(pts
						(arc
							(start -0.1778 -0.5715)
							(mid -0.321484 -0.511984)
							(end -0.381 -0.3683)
						)
						(arc
							(start -0.381 0.3683)
							(mid -0.321484 0.511984)
							(end -0.1778 0.5715)
						)
						(arc
							(start 0.1778 0.5715)
							(mid 0.321484 0.511984)
							(end 0.381 0.3683)
						)
						(arc
							(start 0.381 -0.3683)
							(mid 0.321484 -0.511984)
							(end 0.1778 -0.5715)
						)
					)
					(width 0)
					(fill yes)
				)
			)
		)
	)
	(footprint ""
		(layer "B.Cu")
		(at 131.520438 -27.121612 -90)
		(property "Reference" "C28"
			(at 0 0 90)
			(layer "B.SilkS")
			(hide yes)
			(effects
				(font
					(size 1.27 1.27)
				)
				(justify mirror)
			)
		)
		(property "Value" "SCD1U25V2KX-GP"
			(at -1.1811 -2.7051 270)
			(unlocked yes)
			(layer "B.Fab")
			(hide yes)
			(effects
				(font
					(size 1.016 1.016)
					(thickness 0.1524)
				)
				(justify mirror)
			)
		)
		(property "Device Type" "C402H22"
			(at -1.1811 -4.2291 270)
			(unlocked yes)
			(layer "B.Fab")
			(hide yes)
			(effects
				(font
					(size 1.016 1.016)
					(thickness 0.1524)
				)
				(justify mirror)
			)
		)
		(duplicate_pad_numbers_are_jumpers no)
		(fp_rect
			(start 0.4318 0.9525)
			(end -0.4318 -0.9525)
			(stroke
				(width 0)
				(type default)
			)
			(fill no)
			(layer "B.CrtYd")
		)
		(fp_rect
			(start 0.4318 0.9525)
			(end -0.4318 -0.9525)
			(stroke
				(width 0)
				(type default)
			)
			(fill no)
			(layer "B.Fab")
		)
		(pad "1" smd custom
			(at 0 -0.4445 90)
			(size 0.1524 0.1524)
			(layers "B.Cu" "B.Mask" "B.Paste")
			(net "P5V")
			(options
				(clearance outline)
				(anchor circle)
			)
			(primitives
				(gr_poly
					(pts
						(arc
							(start 0.3048 0.2032)
							(mid 0.275042 0.275042)
							(end 0.2032 0.3048)
						)
						(arc
							(start -0.2032 0.3048)
							(mid -0.275042 0.275042)
							(end -0.3048 0.2032)
						)
						(arc
							(start -0.3048 -0.2032)
							(mid -0.275042 -0.275042)
							(end -0.2032 -0.3048)
						)
						(arc
							(start 0.2032 -0.3048)
							(mid 0.275042 -0.275042)
							(end 0.3048 -0.2032)
						)
					)
					(width 0)
					(fill yes)
				)
			)
		)
		(pad "2" smd custom
			(at 0 0.4445 90)
			(size 0.1524 0.1524)
			(layers "B.Cu" "B.Mask" "B.Paste")
			(net "GND")
			(options
				(clearance outline)
				(anchor circle)
			)
			(primitives
				(gr_poly
					(pts
						(arc
							(start 0.3048 0.2032)
							(mid 0.275042 0.275042)
							(end 0.2032 0.3048)
						)
						(arc
							(start -0.2032 0.3048)
							(mid -0.275042 0.275042)
							(end -0.3048 0.2032)
						)
						(arc
							(start -0.3048 -0.2032)
							(mid -0.275042 -0.275042)
							(end -0.2032 -0.3048)
						)
						(arc
							(start 0.2032 -0.3048)
							(mid 0.275042 -0.275042)
							(end 0.3048 -0.2032)
						)
					)
					(width 0)
					(fill yes)
				)
			)
		)
	)
	(footprint ""
		(layer "B.Cu")
		(at 77.214476 -13.901928 90)
		(property "Reference" "PQ1"
			(at 0 0 90)
			(layer "B.SilkS")
			(hide yes)
			(effects
				(font
					(size 1.27 1.27)
				)
				(justify mirror)
			)
		)
		(property "Value" "MMBT3904W-GP-U"
			(at 2.5527 1.3716 90)
			(unlocked yes)
			(layer "B.Fab")
			(hide yes)
			(effects
				(font
					(size 1.016 1.016)
					(thickness 0.1524)
				)
				(justify mirror)
			)
		)
		(property "Device Type" "SOT323CBE2D2H44"
			(at 2.5527 -0.1524 90)
			(unlocked yes)
			(layer "B.Fab")
			(hide yes)
			(effects
				(font
					(size 1.016 1.016)
					(thickness 0.1524)
				)
				(justify mirror)
			)
		)
		(duplicate_pad_numbers_are_jumpers no)
		(fp_line
			(start 1.2573 -1.7399)
			(end -1.2573 -1.7399)
			(stroke
				(width 0.1524)
				(type default)
			)
			(layer "B.SilkS")
		)
		(fp_line
			(start -1.2573 -1.7399)
			(end -1.2573 1.7399)
			(stroke
				(width 0.1524)
				(type default)
			)
			(layer "B.SilkS")
		)
		(fp_line
			(start 1.2573 1.7399)
			(end 1.2573 -1.7399)
			(stroke
				(width 0.1524)
				(type default)
			)
			(layer "B.SilkS")
		)
		(fp_line
			(start -1.2573 1.7399)
			(end 1.2573 1.7399)
			(stroke
				(width 0.1524)
				(type default)
			)
			(layer "B.SilkS")
		)
		(fp_poly
			(pts
				(xy 0.95504 2.1209) (xy 0.65024 1.8161) (xy 0.34544 2.1209)
			)
			(stroke
				(width 0)
				(type default)
			)
			(fill yes)
			(layer "B.SilkS")
		)
		(fp_rect
			(start 1.5113 1.9939)
			(end -1.5113 -1.9939)
			(stroke
				(width 0)
				(type default)
			)
			(fill no)
			(layer "B.CrtYd")
		)
		(fp_poly
			(pts
				(xy 1.5113 1.9939) (xy 1.5113 -1.9939) (xy -1.5113 -1.9939) (xy -1.5113 1.9939)
			)
			(stroke
				(width 0)
				(type default)
			)
			(fill no)
			(layer "B.Fab")
		)
		(pad "B" smd custom
			(at 0.65024 0.9017 270)
			(size 0.1524 0.1524)
			(layers "B.Cu" "B.Mask" "B.Paste")
			(net "P5V_R_E1")
			(options
				(clearance outline)
				(anchor circle)
			)
			(primitives
				(gr_poly
					(pts
						(arc
							(start -0.098298 -0.5842)
							(mid -0.244131 -0.525866)
							(end -0.3048 -0.381)
						)
						(arc
							(start -0.3048 0.381)
							(mid -0.244112 0.525847)
							(end -0.098298 0.5842)
						)
						(arc
							(start 0.098298 0.5842)
							(mid 0.244131 0.525866)
							(end 0.3048 0.381)
						)
						(arc
							(start 0.3048 -0.381)
							(mid 0.244112 -0.525847)
							(end 0.098298 -0.5842)
						)
					)
					(width 0)
					(fill yes)
				)
			)
		)
		(pad "C" smd custom
			(at 0 -0.9017 270)
			(size 0.1524 0.1524)
			(layers "B.Cu" "B.Mask" "B.Paste")
			(net "P5V")
			(options
				(clearance outline)
				(anchor circle)
			)
			(primitives
				(gr_poly
					(pts
						(arc
							(start -0.098298 -0.5842)
							(mid -0.244131 -0.525866)
							(end -0.3048 -0.381)
						)
						(arc
							(start -0.3048 0.381)
							(mid -0.244112 0.525847)
							(end -0.098298 0.5842)
						)
						(arc
							(start 0.098298 0.5842)
							(mid 0.244131 0.525866)
							(end 0.3048 0.381)
						)
						(arc
							(start 0.3048 -0.381)
							(mid 0.244112 -0.525847)
							(end 0.098298 -0.5842)
						)
					)
					(width 0)
					(fill yes)
				)
			)
		)
		(pad "E" smd custom
			(at -0.65024 0.9017 270)
			(size 0.1524 0.1524)
			(layers "B.Cu" "B.Mask" "B.Paste")
			(net "P3V3")
			(options
				(clearance outline)
				(anchor circle)
			)
			(primitives
				(gr_poly
					(pts
						(arc
							(start -0.098298 -0.5842)
							(mid -0.244131 -0.525866)
							(end -0.3048 -0.381)
						)
						(arc
							(start -0.3048 0.381)
							(mid -0.244112 0.525847)
							(end -0.098298 0.5842)
						)
						(arc
							(start 0.098298 0.5842)
							(mid 0.244131 0.525866)
							(end 0.3048 0.381)
						)
						(arc
							(start 0.3048 -0.381)
							(mid 0.244112 -0.525847)
							(end 0.098298 -0.5842)
						)
					)
					(width 0)
					(fill yes)
				)
			)
		)
	)
	(footprint ""
		(layer "B.Cu")
		(at 82.2706 -35.941 90)
		(property "Reference" "D1"
			(at 0 0 90)
			(layer "B.SilkS")
			(hide yes)
			(effects
				(font
					(size 1.27 1.27)
				)
				(justify mirror)
			)
		)
		(property "Value" "LRB551V-30T1G-GP"
			(at 0 -6.7818 90)
			(unlocked yes)
			(layer "B.Fab")
			(hide yes)
			(effects
				(font
					(size 1.016 1.016)
					(thickness 0.1524)
				)
				(justify mirror)
			)
		)
		(property "Device Type" "SOD323AKH44"
			(at 0 -8.6868 90)
			(unlocked yes)
			(layer "B.Fab")
			(hide yes)
			(effects
				(font
					(size 1.016 1.016)
					(thickness 0.1524)
				)
				(justify mirror)
			)
		)
		(duplicate_pad_numbers_are_jumpers no)
		(fp_line
			(start 0.889 -1.9304)
			(end -0.889 -1.9304)
			(stroke
				(width 0.1524)
				(type default)
			)
			(layer "B.SilkS")
		)
		(fp_line
			(start -0.889 -1.9304)
			(end -0.889 2.159)
			(stroke
				(width 0.1524)
				(type default)
			)
			(layer "B.SilkS")
		)
		(fp_line
			(start -0.762 2.0574)
			(end 0.762 2.0574)
			(stroke
				(width 0.508)
				(type default)
			)
			(layer "B.SilkS")
		)
		(fp_line
			(start 0.889 2.159)
			(end 0.889 -1.9304)
			(stroke
				(width 0.1524)
				(type default)
			)
			(layer "B.SilkS")
		)
		(fp_line
			(start -0.889 2.159)
			(end 0.889 2.159)
			(stroke
				(width 0.1524)
				(type default)
			)
			(layer "B.SilkS")
		)
		(fp_rect
			(start 1.016 2.3114)
			(end -1.016 -2.0066)
			(stroke
				(width 0)
				(type default)
			)
			(fill no)
			(layer "B.CrtYd")
		)
		(fp_poly
			(pts
				(xy 1.016 -2.0066) (xy -1.016 -2.0066) (xy -1.016 2.3114) (xy 1.016 2.3114)
			)
			(stroke
				(width 0)
				(type default)
			)
			(fill no)
			(layer "B.Fab")
		)
		(pad "A" smd rect
			(at 0 -1.143 270)
			(size 0.5588 1.016)
			(layers "B.Cu" "B.Mask" "B.Paste")
			(net "SW_SW_R_0")
		)
		(pad "K" smd rect
			(at 0 1.143 270)
			(size 0.5588 1.016)
			(layers "B.Cu" "B.Mask" "B.Paste")
			(net "SW_SW_R_N_0")
		)
	)
	(footprint ""
		(layer "B.Cu")
		(at 71.395082 -7.169912 180)
		(property "Reference" "C517"
			(at 0 0 0)
			(layer "B.SilkS")
			(hide yes)
			(effects
				(font
					(size 1.27 1.27)
				)
				(justify mirror)
			)
		)
		(property "Value" "SCD033U25V2KX-GP"
			(at -1.1811 -2.7051 180)
			(unlocked yes)
			(layer "B.Fab")
			(hide yes)
			(effects
				(font
					(size 1.016 1.016)
					(thickness 0.1524)
				)
				(justify mirror)
			)
		)
		(property "Device Type" "C402H22"
			(at -1.1811 -4.2291 180)
			(unlocked yes)
			(layer "B.Fab")
			(hide yes)
			(effects
				(font
					(size 1.016 1.016)
					(thickness 0.1524)
				)
				(justify mirror)
			)
		)
		(duplicate_pad_numbers_are_jumpers no)
		(fp_rect
			(start 0.4318 0.9525)
			(end -0.4318 -0.9525)
			(stroke
				(width 0)
				(type default)
			)
			(fill no)
			(layer "B.CrtYd")
		)
		(fp_rect
			(start 0.4318 0.9525)
			(end -0.4318 -0.9525)
			(stroke
				(width 0)
				(type default)
			)
			(fill no)
			(layer "B.Fab")
		)
		(pad "1" smd custom
			(at 0 -0.4445)
			(size 0.1524 0.1524)
			(layers "B.Cu" "B.Mask" "B.Paste")
			(net "PWR_EN_L_P5V")
			(options
				(clearance outline)
				(anchor circle)
			)
			(primitives
				(gr_poly
					(pts
						(arc
							(start 0.3048 0.2032)
							(mid 0.275042 0.275042)
							(end 0.2032 0.3048)
						)
						(arc
							(start -0.2032 0.3048)
							(mid -0.275042 0.275042)
							(end -0.3048 0.2032)
						)
						(arc
							(start -0.3048 -0.2032)
							(mid -0.275042 -0.275042)
							(end -0.2032 -0.3048)
						)
						(arc
							(start 0.2032 -0.3048)
							(mid 0.275042 -0.275042)
							(end 0.3048 -0.2032)
						)
					)
					(width 0)
					(fill yes)
				)
			)
		)
		(pad "2" smd custom
			(at 0 0.4445)
			(size 0.1524 0.1524)
			(layers "B.Cu" "B.Mask" "B.Paste")
			(net "GND")
			(options
				(clearance outline)
				(anchor circle)
			)
			(primitives
				(gr_poly
					(pts
						(arc
							(start 0.3048 0.2032)
							(mid 0.275042 0.275042)
							(end 0.2032 0.3048)
						)
						(arc
							(start -0.2032 0.3048)
							(mid -0.275042 0.275042)
							(end -0.3048 0.2032)
						)
						(arc
							(start -0.3048 -0.2032)
							(mid -0.275042 -0.275042)
							(end -0.2032 -0.3048)
						)
						(arc
							(start 0.2032 -0.3048)
							(mid 0.275042 -0.275042)
							(end 0.3048 -0.2032)
						)
					)
					(width 0)
					(fill yes)
				)
			)
		)
	)
)
